(kicad_pcb
	(version 20260206)
	(generator "pcbnew")
	(generator_version "10.0")
	(general
		(thickness 1.6)
		(legacy_teardrops no)
	)
	(paper "A4")
	(title_block
		(title "04192023_DAF0TMB3IC0_F0TG_MB_C_brd_V02_OCP.brd")
		(comment 1 "Grand Teton / footprints 1083-1088 of 8354")
	)
	(layers
		(0 "F.Cu" signal "TOP")
		(4 "In1.Cu" signal "GND")
		(6 "In2.Cu" signal "IN1")
		(8 "In3.Cu" signal "GND1")
		(10 "In4.Cu" signal "IN2")
		(12 "In5.Cu" signal "GND2")
		(14 "In6.Cu" signal "IN3")
		(16 "In7.Cu" signal "GND3")
		(18 "In8.Cu" signal "VCC")
		(20 "In9.Cu" signal "VCC1")
		(22 "In10.Cu" signal "GND4")
		(24 "In11.Cu" signal "IN4")
		(26 "In12.Cu" signal "GND5")
		(28 "In13.Cu" signal "IN5")
		(30 "In14.Cu" signal "GND6")
		(32 "In15.Cu" signal "IN6")
		(34 "In16.Cu" signal "GND7")
		(2 "B.Cu" signal "BOTTOM")
		(9 "F.Adhes" user "F.Adhesive")
		(11 "B.Adhes" user "B.Adhesive")
		(13 "F.Paste" user "Package Geometry/Pastemask Top")
		(15 "B.Paste" user "Package Geometry/Pastemask Bottom")
		(5 "F.SilkS" user "Ref Des/Silkscreen Top")
		(7 "B.SilkS" user "Ref Des/Silkscreen Bottom")
		(1 "F.Mask" user "Board Geometry/Soldermask Top")
		(3 "B.Mask" user "Board Geometry/Soldermask Bottom")
		(17 "Dwgs.User" user "User.Drawings")
		(19 "Cmts.User" user "User.Comments")
		(21 "Eco1.User" user "User.Eco1")
		(23 "Eco2.User" user "User.Eco2")
		(25 "Edge.Cuts" user "Board Geometry/Outline")
		(27 "Margin" user)
		(31 "F.CrtYd" user "Package Geometry/Place Bound Top")
		(29 "B.CrtYd" user "Package Geometry/Place Bound Bottom")
		(35 "F.Fab" user "Ref Des/Assembly Top")
		(33 "B.Fab" user "Ref Des/Assembly Bottom")
	)
	(footprint ""
		(layer "F.Cu")
		(at 359.710736 -171.23029 -90)
		(property "Reference" "PR501"
			(at 0 0 270)
			(layer "F.SilkS")
			(hide yes)
			(effects
				(font
					(size 1.27 1.27)
				)
			)
		)
		(property "Value" ""
			(at 0 0 270)
			(layer "F.Fab")
			(effects
				(font
					(size 1.27 1.27)
				)
			)
		)
		(duplicate_pad_numbers_are_jumpers no)
		(fp_line
			(start -0.7874 0.4064)
			(end -0.7874 -0.4064)
			(stroke
				(width 0.1524)
				(type default)
			)
			(layer "F.SilkS")
		)
		(fp_line
			(start 0.7874 0.4064)
			(end -0.7874 0.4064)
			(stroke
				(width 0.1524)
				(type default)
			)
			(layer "F.SilkS")
		)
		(fp_line
			(start -0.7874 -0.4064)
			(end 0.7874 -0.4064)
			(stroke
				(width 0.1524)
				(type default)
			)
			(layer "F.SilkS")
		)
		(fp_line
			(start 0.7874 -0.4064)
			(end 0.7874 0.4064)
			(stroke
				(width 0.1524)
				(type default)
			)
			(layer "F.SilkS")
		)
		(fp_line
			(start -0.67945 0.3048)
			(end -0.67945 -0.305054)
			(stroke
				(width 0.1)
				(type default)
			)
			(layer "F.Fab")
		)
		(fp_line
			(start -0.12065 0.3048)
			(end -0.67945 0.3048)
			(stroke
				(width 0.1)
				(type default)
			)
			(layer "F.Fab")
		)
		(fp_line
			(start 0.120396 0.3048)
			(end 0.120396 0.2794)
			(stroke
				(width 0.1)
				(type default)
			)
			(layer "F.Fab")
		)
		(fp_line
			(start 0.67945 0.3048)
			(end 0.120396 0.3048)
			(stroke
				(width 0.1)
				(type default)
			)
			(layer "F.Fab")
		)
		(fp_line
			(start -0.12065 0.2794)
			(end -0.12065 0.3048)
			(stroke
				(width 0.1)
				(type default)
			)
			(layer "F.Fab")
		)
		(fp_line
			(start 0.120396 0.2794)
			(end -0.12065 0.2794)
			(stroke
				(width 0.1)
				(type default)
			)
			(layer "F.Fab")
		)
		(fp_line
			(start -0.12065 -0.2794)
			(end 0.12065 -0.2794)
			(stroke
				(width 0.1)
				(type default)
			)
			(layer "F.Fab")
		)
		(fp_line
			(start 0.12065 -0.2794)
			(end 0.12065 -0.3048)
			(stroke
				(width 0.1)
				(type default)
			)
			(layer "F.Fab")
		)
		(fp_line
			(start 0.12065 -0.3048)
			(end 0.67945 -0.3048)
			(stroke
				(width 0.1)
				(type default)
			)
			(layer "F.Fab")
		)
		(fp_line
			(start 0.67945 -0.3048)
			(end 0.67945 0.3048)
			(stroke
				(width 0.1)
				(type default)
			)
			(layer "F.Fab")
		)
		(fp_line
			(start -0.67945 -0.305054)
			(end -0.12065 -0.305054)
			(stroke
				(width 0.1)
				(type default)
			)
			(layer "F.Fab")
		)
		(fp_line
			(start -0.12065 -0.305054)
			(end -0.12065 -0.2794)
			(stroke
				(width 0.1)
				(type default)
			)
			(layer "F.Fab")
		)
		(pad "1" smd circle
			(at -0.40005 0 270)
			(size 0 0)
			(layers "F.Cu" "F.Mask" "F.Paste")
			(net "SW_PVDDCR_CPU0_P0_SW5_RC")
		)
		(pad "2" smd circle
			(at 0.40005 0 270)
			(size 0 0)
			(layers "F.Cu" "F.Mask" "F.Paste")
			(net "GND")
		)
	)
	(footprint ""
		(layer "F.Cu")
		(at 178.72456 -396.385542)
		(property "Reference" "PR3930"
			(at 0 0 0)
			(layer "F.SilkS")
			(hide yes)
			(effects
				(font
					(size 1.27 1.27)
				)
			)
		)
		(property "Value" ""
			(at 0 0 0)
			(layer "F.Fab")
			(effects
				(font
					(size 1.27 1.27)
				)
			)
		)
		(duplicate_pad_numbers_are_jumpers no)
		(fp_line
			(start -0.7874 -0.4064)
			(end 0.7874 -0.4064)
			(stroke
				(width 0.1524)
				(type default)
			)
			(layer "F.SilkS")
		)
		(fp_line
			(start -0.7874 0.4064)
			(end -0.7874 -0.4064)
			(stroke
				(width 0.1524)
				(type default)
			)
			(layer "F.SilkS")
		)
		(fp_line
			(start 0.7874 -0.4064)
			(end 0.7874 0.4064)
			(stroke
				(width 0.1524)
				(type default)
			)
			(layer "F.SilkS")
		)
		(fp_line
			(start 0.7874 0.4064)
			(end -0.7874 0.4064)
			(stroke
				(width 0.1524)
				(type default)
			)
			(layer "F.SilkS")
		)
		(fp_line
			(start -0.67945 -0.305054)
			(end -0.12065 -0.305054)
			(stroke
				(width 0.1)
				(type default)
			)
			(layer "F.Fab")
		)
		(fp_line
			(start -0.67945 0.3048)
			(end -0.67945 -0.305054)
			(stroke
				(width 0.1)
				(type default)
			)
			(layer "F.Fab")
		)
		(fp_line
			(start -0.12065 -0.305054)
			(end -0.12065 -0.2794)
			(stroke
				(width 0.1)
				(type default)
			)
			(layer "F.Fab")
		)
		(fp_line
			(start -0.12065 -0.2794)
			(end 0.12065 -0.2794)
			(stroke
				(width 0.1)
				(type default)
			)
			(layer "F.Fab")
		)
		(fp_line
			(start -0.12065 0.2794)
			(end -0.12065 0.3048)
			(stroke
				(width 0.1)
				(type default)
			)
			(layer "F.Fab")
		)
		(fp_line
			(start -0.12065 0.3048)
			(end -0.67945 0.3048)
			(stroke
				(width 0.1)
				(type default)
			)
			(layer "F.Fab")
		)
		(fp_line
			(start 0.120396 0.2794)
			(end -0.12065 0.2794)
			(stroke
				(width 0.1)
				(type default)
			)
			(layer "F.Fab")
		)
		(fp_line
			(start 0.120396 0.3048)
			(end 0.120396 0.2794)
			(stroke
				(width 0.1)
				(type default)
			)
			(layer "F.Fab")
		)
		(fp_line
			(start 0.12065 -0.3048)
			(end 0.67945 -0.3048)
			(stroke
				(width 0.1)
				(type default)
			)
			(layer "F.Fab")
		)
		(fp_line
			(start 0.12065 -0.2794)
			(end 0.12065 -0.3048)
			(stroke
				(width 0.1)
				(type default)
			)
			(layer "F.Fab")
		)
		(fp_line
			(start 0.67945 -0.3048)
			(end 0.67945 0.3048)
			(stroke
				(width 0.1)
				(type default)
			)
			(layer "F.Fab")
		)
		(fp_line
			(start 0.67945 0.3048)
			(end 0.120396 0.3048)
			(stroke
				(width 0.1)
				(type default)
			)
			(layer "F.Fab")
		)
		(pad "1" smd circle
			(at -0.40005 0)
			(size 0 0)
			(layers "F.Cu" "F.Mask" "F.Paste")
			(net "AGND_HSC")
		)
		(pad "2" smd circle
			(at 0.40005 0)
			(size 0 0)
			(layers "F.Cu" "F.Mask" "F.Paste")
			(net "HSC_ADDR")
		)
	)
	(footprint ""
		(layer "F.Cu")
		(at 449.443602 -426.255688)
		(property "Reference" "PC6602"
			(at 0 0 0)
			(layer "F.SilkS")
			(hide yes)
			(effects
				(font
					(size 1.27 1.27)
				)
			)
		)
		(property "Value" ""
			(at 0 0 0)
			(layer "F.Fab")
			(effects
				(font
					(size 1.27 1.27)
				)
			)
		)
		(duplicate_pad_numbers_are_jumpers no)
		(fp_line
			(start -0.7874 -0.4064)
			(end 0.7874 -0.4064)
			(stroke
				(width 0.1524)
				(type default)
			)
			(layer "F.SilkS")
		)
		(fp_line
			(start -0.7874 0.4064)
			(end -0.7874 -0.4064)
			(stroke
				(width 0.1524)
				(type default)
			)
			(layer "F.SilkS")
		)
		(fp_line
			(start 0.7874 -0.4064)
			(end 0.7874 0.4064)
			(stroke
				(width 0.1524)
				(type default)
			)
			(layer "F.SilkS")
		)
		(fp_line
			(start 0.7874 0.4064)
			(end -0.7874 0.4064)
			(stroke
				(width 0.1524)
				(type default)
			)
			(layer "F.SilkS")
		)
		(fp_line
			(start -0.67945 -0.305054)
			(end -0.12065 -0.305054)
			(stroke
				(width 0.1)
				(type default)
			)
			(layer "F.Fab")
		)
		(fp_line
			(start -0.67945 0.3048)
			(end -0.67945 -0.305054)
			(stroke
				(width 0.1)
				(type default)
			)
			(layer "F.Fab")
		)
		(fp_line
			(start -0.12065 -0.305054)
			(end -0.12065 -0.2794)
			(stroke
				(width 0.1)
				(type default)
			)
			(layer "F.Fab")
		)
		(fp_line
			(start -0.12065 -0.2794)
			(end 0.12065 -0.2794)
			(stroke
				(width 0.1)
				(type default)
			)
			(layer "F.Fab")
		)
		(fp_line
			(start -0.12065 0.2794)
			(end -0.12065 0.3048)
			(stroke
				(width 0.1)
				(type default)
			)
			(layer "F.Fab")
		)
		(fp_line
			(start -0.12065 0.3048)
			(end -0.67945 0.3048)
			(stroke
				(width 0.1)
				(type default)
			)
			(layer "F.Fab")
		)
		(fp_line
			(start 0.120396 0.2794)
			(end -0.12065 0.2794)
			(stroke
				(width 0.1)
				(type default)
			)
			(layer "F.Fab")
		)
		(fp_line
			(start 0.120396 0.3048)
			(end 0.120396 0.2794)
			(stroke
				(width 0.1)
				(type default)
			)
			(layer "F.Fab")
		)
		(fp_line
			(start 0.12065 -0.3048)
			(end 0.67945 -0.3048)
			(stroke
				(width 0.1)
				(type default)
			)
			(layer "F.Fab")
		)
		(fp_line
			(start 0.12065 -0.2794)
			(end 0.12065 -0.3048)
			(stroke
				(width 0.1)
				(type default)
			)
			(layer "F.Fab")
		)
		(fp_line
			(start 0.67945 -0.3048)
			(end 0.67945 0.3048)
			(stroke
				(width 0.1)
				(type default)
			)
			(layer "F.Fab")
		)
		(fp_line
			(start 0.67945 0.3048)
			(end 0.120396 0.3048)
			(stroke
				(width 0.1)
				(type default)
			)
			(layer "F.Fab")
		)
		(pad "1" smd circle
			(at -0.40005 0)
			(size 0 0)
			(layers "F.Cu" "F.Mask" "F.Paste")
			(net "P0V9_RETIMER_CPU0_VINSEN")
		)
		(pad "2" smd circle
			(at 0.40005 0)
			(size 0 0)
			(layers "F.Cu" "F.Mask" "F.Paste")
			(net "GND")
		)
	)
	(footprint ""
		(layer "F.Cu")
		(at 442.18352 -438.397396)
		(property "Reference" "Q136"
			(at -1.4224 -1.768348 0)
			(unlocked yes)
			(layer "F.SilkS")
			(effects
				(font
					(size 0.7874 0.5842)
					(thickness 0.1524)
				)
				(justify left)
			)
		)
		(property "Value" ""
			(at 0 0 0)
			(layer "F.Fab")
			(effects
				(font
					(size 1.27 1.27)
				)
			)
		)
		(duplicate_pad_numbers_are_jumpers no)
		(fp_line
			(start -1.332738 -1.100074)
			(end -0.4826 -1.100074)
			(stroke
				(width 0.1524)
				(type default)
			)
			(layer "F.SilkS")
		)
		(fp_line
			(start -1.332738 1.100074)
			(end -1.332738 -1.100074)
			(stroke
				(width 0.1524)
				(type default)
			)
			(layer "F.SilkS")
		)
		(fp_line
			(start -0.4826 -1.100074)
			(end 0 -0.541274)
			(stroke
				(width 0.1524)
				(type default)
			)
			(layer "F.SilkS")
		)
		(fp_line
			(start 0 -0.541274)
			(end 0.4826 -1.100074)
			(stroke
				(width 0.1524)
				(type default)
			)
			(layer "F.SilkS")
		)
		(fp_line
			(start 0.4826 -1.100074)
			(end 1.332738 -1.100074)
			(stroke
				(width 0.1524)
				(type default)
			)
			(layer "F.SilkS")
		)
		(fp_line
			(start 1.332738 -1.100074)
			(end 1.332738 1.100074)
			(stroke
				(width 0.1524)
				(type default)
			)
			(layer "F.SilkS")
		)
		(fp_line
			(start 1.332738 1.100074)
			(end -1.332738 1.100074)
			(stroke
				(width 0.1524)
				(type default)
			)
			(layer "F.SilkS")
		)
		(fp_poly
			(pts
				(xy -1.467104 -1.284986) (xy -2.16916 -0.933958) (xy -2.16916 -1.636014)
			)
			(stroke
				(width 0)
				(type default)
			)
			(fill yes)
			(layer "F.SilkS")
		)
		(fp_line
			(start -0.674878 -1.100074)
			(end 0.674878 -1.100074)
			(stroke
				(width 0.1)
				(type default)
			)
			(layer "F.Fab")
		)
		(fp_line
			(start -0.674878 1.100074)
			(end -0.674878 -1.100074)
			(stroke
				(width 0.1)
				(type default)
			)
			(layer "F.Fab")
		)
		(fp_line
			(start 0.674878 -1.100074)
			(end 0.674878 1.100074)
			(stroke
				(width 0.1)
				(type default)
			)
			(layer "F.Fab")
		)
		(fp_line
			(start 0.674878 1.100074)
			(end -0.674878 1.100074)
			(stroke
				(width 0.1)
				(type default)
			)
			(layer "F.Fab")
		)
		(fp_poly
			(pts
				(xy -2.2352 -0.298958) (xy -2.2352 -1.001014) (xy -1.533144 -0.649986)
			)
			(stroke
				(width 0)
				(type default)
			)
			(fill yes)
			(layer "F.Fab")
		)
		(pad "1" smd rect
			(at -0.94996 -0.649986 90)
			(size 0.4318 0.508)
			(layers "F.Cu" "F.Mask" "F.Paste")
			(net "GND")
		)
		(pad "2" smd rect
			(at -0.94996 0 90)
			(size 0.4318 0.508)
			(layers "F.Cu" "F.Mask" "F.Paste")
			(net "GPU_3V3IO_RSVD4")
		)
		(pad "3" smd rect
			(at -0.94996 0.649986 90)
			(size 0.4318 0.508)
			(layers "F.Cu" "F.Mask" "F.Paste")
			(net "GPU_3V3IO_RSVD4_ISO")
		)
		(pad "4" smd rect
			(at 0.94996 0.649986 90)
			(size 0.4318 0.508)
			(layers "F.Cu" "F.Mask" "F.Paste")
			(net "GND")
		)
		(pad "5" smd rect
			(at 0.94996 0 90)
			(size 0.4318 0.508)
			(layers "F.Cu" "F.Mask" "F.Paste")
			(net "GPU_3V3IO_RSVD4_N")
		)
		(pad "6" smd rect
			(at 0.94996 -0.649986 90)
			(size 0.4318 0.508)
			(layers "F.Cu" "F.Mask" "F.Paste")
			(net "GPU_3V3IO_RSVD4_N")
		)
	)
	(footprint ""
		(layer "F.Cu")
		(at 456.131676 -401.709128 -90)
		(property "Reference" "PC6584"
			(at 0 0 270)
			(layer "F.SilkS")
			(hide yes)
			(effects
				(font
					(size 1.27 1.27)
				)
			)
		)
		(property "Value" ""
			(at 0 0 270)
			(layer "F.Fab")
			(effects
				(font
					(size 1.27 1.27)
				)
			)
		)
		(duplicate_pad_numbers_are_jumpers no)
		(fp_line
			(start -0.7874 0.4064)
			(end -0.7874 -0.4064)
			(stroke
				(width 0.1524)
				(type default)
			)
			(layer "F.SilkS")
		)
		(fp_line
			(start 0.7874 0.4064)
			(end -0.7874 0.4064)
			(stroke
				(width 0.1524)
				(type default)
			)
			(layer "F.SilkS")
		)
		(fp_line
			(start -0.7874 -0.4064)
			(end 0.7874 -0.4064)
			(stroke
				(width 0.1524)
				(type default)
			)
			(layer "F.SilkS")
		)
		(fp_line
			(start 0.7874 -0.4064)
			(end 0.7874 0.4064)
			(stroke
				(width 0.1524)
				(type default)
			)
			(layer "F.SilkS")
		)
		(fp_line
			(start -0.67945 0.3048)
			(end -0.67945 -0.305054)
			(stroke
				(width 0.1)
				(type default)
			)
			(layer "F.Fab")
		)
		(fp_line
			(start -0.12065 0.3048)
			(end -0.67945 0.3048)
			(stroke
				(width 0.1)
				(type default)
			)
			(layer "F.Fab")
		)
		(fp_line
			(start 0.120396 0.3048)
			(end 0.120396 0.2794)
			(stroke
				(width 0.1)
				(type default)
			)
			(layer "F.Fab")
		)
		(fp_line
			(start 0.67945 0.3048)
			(end 0.120396 0.3048)
			(stroke
				(width 0.1)
				(type default)
			)
			(layer "F.Fab")
		)
		(fp_line
			(start -0.12065 0.2794)
			(end -0.12065 0.3048)
			(stroke
				(width 0.1)
				(type default)
			)
			(layer "F.Fab")
		)
		(fp_line
			(start 0.120396 0.2794)
			(end -0.12065 0.2794)
			(stroke
				(width 0.1)
				(type default)
			)
			(layer "F.Fab")
		)
		(fp_line
			(start -0.12065 -0.2794)
			(end 0.12065 -0.2794)
			(stroke
				(width 0.1)
				(type default)
			)
			(layer "F.Fab")
		)
		(fp_line
			(start 0.12065 -0.2794)
			(end 0.12065 -0.3048)
			(stroke
				(width 0.1)
				(type default)
			)
			(layer "F.Fab")
		)
		(fp_line
			(start 0.12065 -0.3048)
			(end 0.67945 -0.3048)
			(stroke
				(width 0.1)
				(type default)
			)
			(layer "F.Fab")
		)
		(fp_line
			(start 0.67945 -0.3048)
			(end 0.67945 0.3048)
			(stroke
				(width 0.1)
				(type default)
			)
			(layer "F.Fab")
		)
		(fp_line
			(start -0.67945 -0.305054)
			(end -0.12065 -0.305054)
			(stroke
				(width 0.1)
				(type default)
			)
			(layer "F.Fab")
		)
		(fp_line
			(start -0.12065 -0.305054)
			(end -0.12065 -0.2794)
			(stroke
				(width 0.1)
				(type default)
			)
			(layer "F.Fab")
		)
		(pad "1" smd circle
			(at -0.40005 0 270)
			(size 0 0)
			(layers "F.Cu" "F.Mask" "F.Paste")
			(net "SW_P0V9_RETIMER_CPU0_BOOT2_RC")
		)
		(pad "2" smd circle
			(at 0.40005 0 270)
			(size 0 0)
			(layers "F.Cu" "F.Mask" "F.Paste")
			(net "SW_P0V9_RETIMER_CPU0_PH2")
		)
	)
	(footprint ""
		(layer "F.Cu")
		(at 190.119 -137.632948 -90)
		(property "Reference" "R1447"
			(at 0 0 270)
			(layer "F.SilkS")
			(hide yes)
			(effects
				(font
					(size 1.27 1.27)
				)
			)
		)
		(property "Value" ""
			(at 0 0 270)
			(layer "F.Fab")
			(effects
				(font
					(size 1.27 1.27)
				)
			)
		)
		(duplicate_pad_numbers_are_jumpers no)
		(fp_line
			(start -0.7874 0.4064)
			(end -0.7874 -0.4064)
			(stroke
				(width 0.1524)
				(type default)
			)
			(layer "F.SilkS")
		)
		(fp_line
			(start 0.7874 0.4064)
			(end -0.7874 0.4064)
			(stroke
				(width 0.1524)
				(type default)
			)
			(layer "F.SilkS")
		)
		(fp_line
			(start -0.7874 -0.4064)
			(end 0.7874 -0.4064)
			(stroke
				(width 0.1524)
				(type default)
			)
			(layer "F.SilkS")
		)
		(fp_line
			(start 0.7874 -0.4064)
			(end 0.7874 0.4064)
			(stroke
				(width 0.1524)
				(type default)
			)
			(layer "F.SilkS")
		)
		(fp_line
			(start -0.67945 0.3048)
			(end -0.67945 -0.305054)
			(stroke
				(width 0.1)
				(type default)
			)
			(layer "F.Fab")
		)
		(fp_line
			(start -0.12065 0.3048)
			(end -0.67945 0.3048)
			(stroke
				(width 0.1)
				(type default)
			)
			(layer "F.Fab")
		)
		(fp_line
			(start 0.120396 0.3048)
			(end 0.120396 0.2794)
			(stroke
				(width 0.1)
				(type default)
			)
			(layer "F.Fab")
		)
		(fp_line
			(start 0.67945 0.3048)
			(end 0.120396 0.3048)
			(stroke
				(width 0.1)
				(type default)
			)
			(layer "F.Fab")
		)
		(fp_line
			(start -0.12065 0.2794)
			(end -0.12065 0.3048)
			(stroke
				(width 0.1)
				(type default)
			)
			(layer "F.Fab")
		)
		(fp_line
			(start 0.120396 0.2794)
			(end -0.12065 0.2794)
			(stroke
				(width 0.1)
				(type default)
			)
			(layer "F.Fab")
		)
		(fp_line
			(start -0.12065 -0.2794)
			(end 0.12065 -0.2794)
			(stroke
				(width 0.1)
				(type default)
			)
			(layer "F.Fab")
		)
		(fp_line
			(start 0.12065 -0.2794)
			(end 0.12065 -0.3048)
			(stroke
				(width 0.1)
				(type default)
			)
			(layer "F.Fab")
		)
		(fp_line
			(start 0.12065 -0.3048)
			(end 0.67945 -0.3048)
			(stroke
				(width 0.1)
				(type default)
			)
			(layer "F.Fab")
		)
		(fp_line
			(start 0.67945 -0.3048)
			(end 0.67945 0.3048)
			(stroke
				(width 0.1)
				(type default)
			)
			(layer "F.Fab")
		)
		(fp_line
			(start -0.67945 -0.305054)
			(end -0.12065 -0.305054)
			(stroke
				(width 0.1)
				(type default)
			)
			(layer "F.Fab")
		)
		(fp_line
			(start -0.12065 -0.305054)
			(end -0.12065 -0.2794)
			(stroke
				(width 0.1)
				(type default)
			)
			(layer "F.Fab")
		)
		(pad "1" smd circle
			(at -0.40005 0 270)
			(size 0 0)
			(layers "F.Cu" "F.Mask" "F.Paste")
			(net "SMB_CPU_5_SCL")
		)
		(pad "2" smd circle
			(at 0.40005 0 270)
			(size 0 0)
			(layers "F.Cu" "F.Mask" "F.Paste")
			(net "SMB_CPU_5_R1_SCL")
		)
	)
)
